(kicad_pcb
	(version 20260206)
	(generator "pcbnew")
	(generator_version "10.0")
	(general
		(thickness 1.6)
		(legacy_teardrops no)
	)
	(paper "A4")
	(title_block
		(title "01162023_DA0F0TEBIF0_F0T_Expander_BD_F_brd_V02_OCP.brd")
		(comment 1 "Grand Teton / footprints 7072-7078 of 9728")
	)
	(layers
		(0 "F.Cu" signal "TOP")
		(4 "In1.Cu" signal "GND")
		(6 "In2.Cu" signal "VCC")
		(8 "In3.Cu" signal "VCC1")
		(10 "In4.Cu" signal "GND1")
		(12 "In5.Cu" signal "IN1")
		(14 "In6.Cu" signal "GND2")
		(16 "In7.Cu" signal "IN2")
		(18 "In8.Cu" signal "GND3")
		(20 "In9.Cu" signal "IN3")
		(22 "In10.Cu" signal "GND4")
		(24 "In11.Cu" signal "IN4")
		(26 "In12.Cu" signal "GND5")
		(28 "In13.Cu" signal "IN5")
		(30 "In14.Cu" signal "GND6")
		(32 "In15.Cu" signal "IN6")
		(34 "In16.Cu" signal "GND7")
		(2 "B.Cu" signal "BOTTOM")
		(9 "F.Adhes" user "F.Adhesive")
		(11 "B.Adhes" user "B.Adhesive")
		(13 "F.Paste" user "Package Geometry/Pastemask Top")
		(15 "B.Paste" user "Package Geometry/Pastemask Bottom")
		(5 "F.SilkS" user "Ref Des/Silkscreen Top")
		(7 "B.SilkS" user "Ref Des/Silkscreen Bottom")
		(1 "F.Mask" user "Board Geometry/Soldermask Top")
		(3 "B.Mask" user "Board Geometry/Soldermask Bottom")
		(17 "Dwgs.User" user "User.Drawings")
		(19 "Cmts.User" user "User.Comments")
		(21 "Eco1.User" user "User.Eco1")
		(23 "Eco2.User" user "User.Eco2")
		(25 "Edge.Cuts" user "Board Geometry/Outline")
		(27 "Margin" user)
		(31 "F.CrtYd" user "Package Geometry/Place Bound Top")
		(29 "B.CrtYd" user "Package Geometry/Place Bound Bottom")
		(35 "F.Fab" user "Ref Des/Assembly Top")
		(33 "B.Fab" user "Ref Des/Assembly Bottom")
	)
	(footprint ""
		(layer "F.Cu")
		(at 365.506 -209.931 180)
		(property "Reference" "R4625"
			(at 0 0 180)
			(layer "F.SilkS")
			(hide yes)
			(effects
				(font
					(size 1.27 1.27)
				)
			)
		)
		(property "Value" ""
			(at 0 0 180)
			(layer "F.Fab")
			(effects
				(font
					(size 1.27 1.27)
				)
			)
		)
		(duplicate_pad_numbers_are_jumpers no)
		(fp_line
			(start 0.7874 0.4064)
			(end -0.7874 0.4064)
			(stroke
				(width 0.1524)
				(type default)
			)
			(layer "F.SilkS")
		)
		(fp_line
			(start 0.7874 -0.4064)
			(end 0.7874 0.4064)
			(stroke
				(width 0.1524)
				(type default)
			)
			(layer "F.SilkS")
		)
		(fp_line
			(start -0.7874 0.4064)
			(end -0.7874 -0.4064)
			(stroke
				(width 0.1524)
				(type default)
			)
			(layer "F.SilkS")
		)
		(fp_line
			(start -0.7874 -0.4064)
			(end 0.7874 -0.4064)
			(stroke
				(width 0.1524)
				(type default)
			)
			(layer "F.SilkS")
		)
		(fp_line
			(start 0.67945 0.3048)
			(end 0.120396 0.3048)
			(stroke
				(width 0.1)
				(type default)
			)
			(layer "F.Fab")
		)
		(fp_line
			(start 0.67945 -0.3048)
			(end 0.67945 0.3048)
			(stroke
				(width 0.1)
				(type default)
			)
			(layer "F.Fab")
		)
		(fp_line
			(start 0.12065 -0.2794)
			(end 0.12065 -0.3048)
			(stroke
				(width 0.1)
				(type default)
			)
			(layer "F.Fab")
		)
		(fp_line
			(start 0.12065 -0.3048)
			(end 0.67945 -0.3048)
			(stroke
				(width 0.1)
				(type default)
			)
			(layer "F.Fab")
		)
		(fp_line
			(start 0.120396 0.3048)
			(end 0.120396 0.2794)
			(stroke
				(width 0.1)
				(type default)
			)
			(layer "F.Fab")
		)
		(fp_line
			(start 0.120396 0.2794)
			(end -0.12065 0.2794)
			(stroke
				(width 0.1)
				(type default)
			)
			(layer "F.Fab")
		)
		(fp_line
			(start -0.12065 0.3048)
			(end -0.67945 0.3048)
			(stroke
				(width 0.1)
				(type default)
			)
			(layer "F.Fab")
		)
		(fp_line
			(start -0.12065 0.2794)
			(end -0.12065 0.3048)
			(stroke
				(width 0.1)
				(type default)
			)
			(layer "F.Fab")
		)
		(fp_line
			(start -0.12065 -0.2794)
			(end 0.12065 -0.2794)
			(stroke
				(width 0.1)
				(type default)
			)
			(layer "F.Fab")
		)
		(fp_line
			(start -0.12065 -0.305054)
			(end -0.12065 -0.2794)
			(stroke
				(width 0.1)
				(type default)
			)
			(layer "F.Fab")
		)
		(fp_line
			(start -0.67945 0.3048)
			(end -0.67945 -0.305054)
			(stroke
				(width 0.1)
				(type default)
			)
			(layer "F.Fab")
		)
		(fp_line
			(start -0.67945 -0.305054)
			(end -0.12065 -0.305054)
			(stroke
				(width 0.1)
				(type default)
			)
			(layer "F.Fab")
		)
		(pad "1" smd circle
			(at -0.40005 0 180)
			(size 0 0)
			(layers "F.Cu" "F.Mask" "F.Paste")
			(net "RST_PEX_SSD0_PERST_N")
		)
		(pad "2" smd circle
			(at 0.40005 0 180)
			(size 0 0)
			(layers "F.Cu" "F.Mask" "F.Paste")
			(net "RST_PEX_SSD0_PERST_R_N")
		)
	)
	(footprint ""
		(layer "F.Cu")
		(at 307.867812 -18.437098)
		(property "Reference" "R1707"
			(at 0 0 0)
			(layer "F.SilkS")
			(hide yes)
			(effects
				(font
					(size 1.27 1.27)
				)
			)
		)
		(property "Value" ""
			(at 0 0 0)
			(layer "F.Fab")
			(effects
				(font
					(size 1.27 1.27)
				)
			)
		)
		(duplicate_pad_numbers_are_jumpers no)
		(fp_line
			(start -0.7874 -0.4064)
			(end 0.7874 -0.4064)
			(stroke
				(width 0.1524)
				(type default)
			)
			(layer "F.SilkS")
		)
		(fp_line
			(start -0.7874 0.4064)
			(end -0.7874 -0.4064)
			(stroke
				(width 0.1524)
				(type default)
			)
			(layer "F.SilkS")
		)
		(fp_line
			(start 0.7874 -0.4064)
			(end 0.7874 0.4064)
			(stroke
				(width 0.1524)
				(type default)
			)
			(layer "F.SilkS")
		)
		(fp_line
			(start 0.7874 0.4064)
			(end -0.7874 0.4064)
			(stroke
				(width 0.1524)
				(type default)
			)
			(layer "F.SilkS")
		)
		(fp_line
			(start -0.67945 -0.305054)
			(end -0.12065 -0.305054)
			(stroke
				(width 0.1)
				(type default)
			)
			(layer "F.Fab")
		)
		(fp_line
			(start -0.67945 0.3048)
			(end -0.67945 -0.305054)
			(stroke
				(width 0.1)
				(type default)
			)
			(layer "F.Fab")
		)
		(fp_line
			(start -0.12065 -0.305054)
			(end -0.12065 -0.2794)
			(stroke
				(width 0.1)
				(type default)
			)
			(layer "F.Fab")
		)
		(fp_line
			(start -0.12065 -0.2794)
			(end 0.12065 -0.2794)
			(stroke
				(width 0.1)
				(type default)
			)
			(layer "F.Fab")
		)
		(fp_line
			(start -0.12065 0.2794)
			(end -0.12065 0.3048)
			(stroke
				(width 0.1)
				(type default)
			)
			(layer "F.Fab")
		)
		(fp_line
			(start -0.12065 0.3048)
			(end -0.67945 0.3048)
			(stroke
				(width 0.1)
				(type default)
			)
			(layer "F.Fab")
		)
		(fp_line
			(start 0.120396 0.2794)
			(end -0.12065 0.2794)
			(stroke
				(width 0.1)
				(type default)
			)
			(layer "F.Fab")
		)
		(fp_line
			(start 0.120396 0.3048)
			(end 0.120396 0.2794)
			(stroke
				(width 0.1)
				(type default)
			)
			(layer "F.Fab")
		)
		(fp_line
			(start 0.12065 -0.3048)
			(end 0.67945 -0.3048)
			(stroke
				(width 0.1)
				(type default)
			)
			(layer "F.Fab")
		)
		(fp_line
			(start 0.12065 -0.2794)
			(end 0.12065 -0.3048)
			(stroke
				(width 0.1)
				(type default)
			)
			(layer "F.Fab")
		)
		(fp_line
			(start 0.67945 -0.3048)
			(end 0.67945 0.3048)
			(stroke
				(width 0.1)
				(type default)
			)
			(layer "F.Fab")
		)
		(fp_line
			(start 0.67945 0.3048)
			(end 0.120396 0.3048)
			(stroke
				(width 0.1)
				(type default)
			)
			(layer "F.Fab")
		)
		(pad "1" smd circle
			(at -0.40005 0)
			(size 0 0)
			(layers "F.Cu" "F.Mask" "F.Paste")
			(net "SMB_ISO_SSD10_R_SCL")
		)
		(pad "2" smd circle
			(at 0.40005 0)
			(size 0 0)
			(layers "F.Cu" "F.Mask" "F.Paste")
			(net "SMB_ISO_SSD10_SCL")
		)
	)
	(footprint ""
		(layer "F.Cu")
		(at 446.974976 -56.977534 180)
		(property "Reference" "PC438"
			(at 0 0 180)
			(layer "F.SilkS")
			(hide yes)
			(effects
				(font
					(size 1.27 1.27)
				)
			)
		)
		(property "Value" ""
			(at 0 0 180)
			(layer "F.Fab")
			(effects
				(font
					(size 1.27 1.27)
				)
			)
		)
		(duplicate_pad_numbers_are_jumpers no)
		(fp_line
			(start 0.7874 0.4064)
			(end -0.7874 0.4064)
			(stroke
				(width 0.1524)
				(type default)
			)
			(layer "F.SilkS")
		)
		(fp_line
			(start 0.7874 -0.4064)
			(end 0.7874 0.4064)
			(stroke
				(width 0.1524)
				(type default)
			)
			(layer "F.SilkS")
		)
		(fp_line
			(start -0.7874 0.4064)
			(end -0.7874 -0.4064)
			(stroke
				(width 0.1524)
				(type default)
			)
			(layer "F.SilkS")
		)
		(fp_line
			(start -0.7874 -0.4064)
			(end 0.7874 -0.4064)
			(stroke
				(width 0.1524)
				(type default)
			)
			(layer "F.SilkS")
		)
		(fp_line
			(start 0.67945 0.3048)
			(end 0.120396 0.3048)
			(stroke
				(width 0.1)
				(type default)
			)
			(layer "F.Fab")
		)
		(fp_line
			(start 0.67945 -0.3048)
			(end 0.67945 0.3048)
			(stroke
				(width 0.1)
				(type default)
			)
			(layer "F.Fab")
		)
		(fp_line
			(start 0.12065 -0.2794)
			(end 0.12065 -0.3048)
			(stroke
				(width 0.1)
				(type default)
			)
			(layer "F.Fab")
		)
		(fp_line
			(start 0.12065 -0.3048)
			(end 0.67945 -0.3048)
			(stroke
				(width 0.1)
				(type default)
			)
			(layer "F.Fab")
		)
		(fp_line
			(start 0.120396 0.3048)
			(end 0.120396 0.2794)
			(stroke
				(width 0.1)
				(type default)
			)
			(layer "F.Fab")
		)
		(fp_line
			(start 0.120396 0.2794)
			(end -0.12065 0.2794)
			(stroke
				(width 0.1)
				(type default)
			)
			(layer "F.Fab")
		)
		(fp_line
			(start -0.12065 0.3048)
			(end -0.67945 0.3048)
			(stroke
				(width 0.1)
				(type default)
			)
			(layer "F.Fab")
		)
		(fp_line
			(start -0.12065 0.2794)
			(end -0.12065 0.3048)
			(stroke
				(width 0.1)
				(type default)
			)
			(layer "F.Fab")
		)
		(fp_line
			(start -0.12065 -0.2794)
			(end 0.12065 -0.2794)
			(stroke
				(width 0.1)
				(type default)
			)
			(layer "F.Fab")
		)
		(fp_line
			(start -0.12065 -0.305054)
			(end -0.12065 -0.2794)
			(stroke
				(width 0.1)
				(type default)
			)
			(layer "F.Fab")
		)
		(fp_line
			(start -0.67945 0.3048)
			(end -0.67945 -0.305054)
			(stroke
				(width 0.1)
				(type default)
			)
			(layer "F.Fab")
		)
		(fp_line
			(start -0.67945 -0.305054)
			(end -0.12065 -0.305054)
			(stroke
				(width 0.1)
				(type default)
			)
			(layer "F.Fab")
		)
		(pad "1" smd circle
			(at -0.40005 0 180)
			(size 0 0)
			(layers "F.Cu" "F.Mask" "F.Paste")
			(net "P12V_AUX")
		)
		(pad "2" smd circle
			(at 0.40005 0 180)
			(size 0 0)
			(layers "F.Cu" "F.Mask" "F.Paste")
			(net "GND")
		)
	)
	(footprint ""
		(layer "F.Cu")
		(at 449.452238 -95.264224 90)
		(property "Reference" "R4457"
			(at 0 0 90)
			(layer "F.SilkS")
			(hide yes)
			(effects
				(font
					(size 1.27 1.27)
				)
			)
		)
		(property "Value" ""
			(at 0 0 90)
			(layer "F.Fab")
			(effects
				(font
					(size 1.27 1.27)
				)
			)
		)
		(duplicate_pad_numbers_are_jumpers no)
		(fp_line
			(start 0.7874 -0.4064)
			(end 0.7874 0.4064)
			(stroke
				(width 0.1524)
				(type default)
			)
			(layer "F.SilkS")
		)
		(fp_line
			(start -0.7874 -0.4064)
			(end 0.7874 -0.4064)
			(stroke
				(width 0.1524)
				(type default)
			)
			(layer "F.SilkS")
		)
		(fp_line
			(start 0.7874 0.4064)
			(end -0.7874 0.4064)
			(stroke
				(width 0.1524)
				(type default)
			)
			(layer "F.SilkS")
		)
		(fp_line
			(start -0.7874 0.4064)
			(end -0.7874 -0.4064)
			(stroke
				(width 0.1524)
				(type default)
			)
			(layer "F.SilkS")
		)
		(fp_line
			(start -0.12065 -0.305054)
			(end -0.12065 -0.2794)
			(stroke
				(width 0.1)
				(type default)
			)
			(layer "F.Fab")
		)
		(fp_line
			(start -0.67945 -0.305054)
			(end -0.12065 -0.305054)
			(stroke
				(width 0.1)
				(type default)
			)
			(layer "F.Fab")
		)
		(fp_line
			(start 0.67945 -0.3048)
			(end 0.67945 0.3048)
			(stroke
				(width 0.1)
				(type default)
			)
			(layer "F.Fab")
		)
		(fp_line
			(start 0.12065 -0.3048)
			(end 0.67945 -0.3048)
			(stroke
				(width 0.1)
				(type default)
			)
			(layer "F.Fab")
		)
		(fp_line
			(start 0.12065 -0.2794)
			(end 0.12065 -0.3048)
			(stroke
				(width 0.1)
				(type default)
			)
			(layer "F.Fab")
		)
		(fp_line
			(start -0.12065 -0.2794)
			(end 0.12065 -0.2794)
			(stroke
				(width 0.1)
				(type default)
			)
			(layer "F.Fab")
		)
		(fp_line
			(start 0.120396 0.2794)
			(end -0.12065 0.2794)
			(stroke
				(width 0.1)
				(type default)
			)
			(layer "F.Fab")
		)
		(fp_line
			(start -0.12065 0.2794)
			(end -0.12065 0.3048)
			(stroke
				(width 0.1)
				(type default)
			)
			(layer "F.Fab")
		)
		(fp_line
			(start 0.67945 0.3048)
			(end 0.120396 0.3048)
			(stroke
				(width 0.1)
				(type default)
			)
			(layer "F.Fab")
		)
		(fp_line
			(start 0.120396 0.3048)
			(end 0.120396 0.2794)
			(stroke
				(width 0.1)
				(type default)
			)
			(layer "F.Fab")
		)
		(fp_line
			(start -0.12065 0.3048)
			(end -0.67945 0.3048)
			(stroke
				(width 0.1)
				(type default)
			)
			(layer "F.Fab")
		)
		(fp_line
			(start -0.67945 0.3048)
			(end -0.67945 -0.305054)
			(stroke
				(width 0.1)
				(type default)
			)
			(layer "F.Fab")
		)
		(pad "1" smd circle
			(at -0.40005 0 90)
			(size 0 0)
			(layers "F.Cu" "F.Mask" "F.Paste")
			(net "HP_NIC7_EN")
		)
		(pad "2" smd circle
			(at 0.40005 0 90)
			(size 0 0)
			(layers "F.Cu" "F.Mask" "F.Paste")
			(net "P12V_NIC7_EN_R")
		)
	)
	(footprint ""
		(layer "F.Cu")
		(at 426.567854 -55.083456)
		(property "Reference" "PC420"
			(at 0 0 0)
			(layer "F.SilkS")
			(hide yes)
			(effects
				(font
					(size 1.27 1.27)
				)
			)
		)
		(property "Value" ""
			(at 0 0 0)
			(layer "F.Fab")
			(effects
				(font
					(size 1.27 1.27)
				)
			)
		)
		(duplicate_pad_numbers_are_jumpers no)
		(fp_line
			(start -0.7874 -0.4064)
			(end 0.7874 -0.4064)
			(stroke
				(width 0.1524)
				(type default)
			)
			(layer "F.SilkS")
		)
		(fp_line
			(start -0.7874 0.4064)
			(end -0.7874 -0.4064)
			(stroke
				(width 0.1524)
				(type default)
			)
			(layer "F.SilkS")
		)
		(fp_line
			(start 0.7874 -0.4064)
			(end 0.7874 0.4064)
			(stroke
				(width 0.1524)
				(type default)
			)
			(layer "F.SilkS")
		)
		(fp_line
			(start 0.7874 0.4064)
			(end -0.7874 0.4064)
			(stroke
				(width 0.1524)
				(type default)
			)
			(layer "F.SilkS")
		)
		(fp_line
			(start -0.67945 -0.305054)
			(end -0.12065 -0.305054)
			(stroke
				(width 0.1)
				(type default)
			)
			(layer "F.Fab")
		)
		(fp_line
			(start -0.67945 0.3048)
			(end -0.67945 -0.305054)
			(stroke
				(width 0.1)
				(type default)
			)
			(layer "F.Fab")
		)
		(fp_line
			(start -0.12065 -0.305054)
			(end -0.12065 -0.2794)
			(stroke
				(width 0.1)
				(type default)
			)
			(layer "F.Fab")
		)
		(fp_line
			(start -0.12065 -0.2794)
			(end 0.12065 -0.2794)
			(stroke
				(width 0.1)
				(type default)
			)
			(layer "F.Fab")
		)
		(fp_line
			(start -0.12065 0.2794)
			(end -0.12065 0.3048)
			(stroke
				(width 0.1)
				(type default)
			)
			(layer "F.Fab")
		)
		(fp_line
			(start -0.12065 0.3048)
			(end -0.67945 0.3048)
			(stroke
				(width 0.1)
				(type default)
			)
			(layer "F.Fab")
		)
		(fp_line
			(start 0.120396 0.2794)
			(end -0.12065 0.2794)
			(stroke
				(width 0.1)
				(type default)
			)
			(layer "F.Fab")
		)
		(fp_line
			(start 0.120396 0.3048)
			(end 0.120396 0.2794)
			(stroke
				(width 0.1)
				(type default)
			)
			(layer "F.Fab")
		)
		(fp_line
			(start 0.12065 -0.3048)
			(end 0.67945 -0.3048)
			(stroke
				(width 0.1)
				(type default)
			)
			(layer "F.Fab")
		)
		(fp_line
			(start 0.12065 -0.2794)
			(end 0.12065 -0.3048)
			(stroke
				(width 0.1)
				(type default)
			)
			(layer "F.Fab")
		)
		(fp_line
			(start 0.67945 -0.3048)
			(end 0.67945 0.3048)
			(stroke
				(width 0.1)
				(type default)
			)
			(layer "F.Fab")
		)
		(fp_line
			(start 0.67945 0.3048)
			(end 0.120396 0.3048)
			(stroke
				(width 0.1)
				(type default)
			)
			(layer "F.Fab")
		)
		(pad "1" smd circle
			(at -0.40005 0)
			(size 0 0)
			(layers "F.Cu" "F.Mask" "F.Paste")
			(net "P5V_AUX")
		)
		(pad "2" smd circle
			(at 0.40005 0)
			(size 0 0)
			(layers "F.Cu" "F.Mask" "F.Paste")
			(net "GND")
		)
	)
	(footprint ""
		(layer "F.Cu")
		(at 3.65125 -393.464542 -90)
		(property "Reference" "R6736"
			(at 0 0 270)
			(layer "F.SilkS")
			(hide yes)
			(effects
				(font
					(size 1.27 1.27)
				)
			)
		)
		(property "Value" ""
			(at 0 0 270)
			(layer "F.Fab")
			(effects
				(font
					(size 1.27 1.27)
				)
			)
		)
		(duplicate_pad_numbers_are_jumpers no)
		(fp_line
			(start -0.7874 0.4064)
			(end -0.7874 -0.4064)
			(stroke
				(width 0.1524)
				(type default)
			)
			(layer "F.SilkS")
		)
		(fp_line
			(start 0.7874 0.4064)
			(end -0.7874 0.4064)
			(stroke
				(width 0.1524)
				(type default)
			)
			(layer "F.SilkS")
		)
		(fp_line
			(start -0.7874 -0.4064)
			(end 0.7874 -0.4064)
			(stroke
				(width 0.1524)
				(type default)
			)
			(layer "F.SilkS")
		)
		(fp_line
			(start 0.7874 -0.4064)
			(end 0.7874 0.4064)
			(stroke
				(width 0.1524)
				(type default)
			)
			(layer "F.SilkS")
		)
		(fp_line
			(start -0.67945 0.3048)
			(end -0.67945 -0.305054)
			(stroke
				(width 0.1)
				(type default)
			)
			(layer "F.Fab")
		)
		(fp_line
			(start -0.12065 0.3048)
			(end -0.67945 0.3048)
			(stroke
				(width 0.1)
				(type default)
			)
			(layer "F.Fab")
		)
		(fp_line
			(start 0.120396 0.3048)
			(end 0.120396 0.2794)
			(stroke
				(width 0.1)
				(type default)
			)
			(layer "F.Fab")
		)
		(fp_line
			(start 0.67945 0.3048)
			(end 0.120396 0.3048)
			(stroke
				(width 0.1)
				(type default)
			)
			(layer "F.Fab")
		)
		(fp_line
			(start -0.12065 0.2794)
			(end -0.12065 0.3048)
			(stroke
				(width 0.1)
				(type default)
			)
			(layer "F.Fab")
		)
		(fp_line
			(start 0.120396 0.2794)
			(end -0.12065 0.2794)
			(stroke
				(width 0.1)
				(type default)
			)
			(layer "F.Fab")
		)
		(fp_line
			(start -0.12065 -0.2794)
			(end 0.12065 -0.2794)
			(stroke
				(width 0.1)
				(type default)
			)
			(layer "F.Fab")
		)
		(fp_line
			(start 0.12065 -0.2794)
			(end 0.12065 -0.3048)
			(stroke
				(width 0.1)
				(type default)
			)
			(layer "F.Fab")
		)
		(fp_line
			(start 0.12065 -0.3048)
			(end 0.67945 -0.3048)
			(stroke
				(width 0.1)
				(type default)
			)
			(layer "F.Fab")
		)
		(fp_line
			(start 0.67945 -0.3048)
			(end 0.67945 0.3048)
			(stroke
				(width 0.1)
				(type default)
			)
			(layer "F.Fab")
		)
		(fp_line
			(start -0.67945 -0.305054)
			(end -0.12065 -0.305054)
			(stroke
				(width 0.1)
				(type default)
			)
			(layer "F.Fab")
		)
		(fp_line
			(start -0.12065 -0.305054)
			(end -0.12065 -0.2794)
			(stroke
				(width 0.1)
				(type default)
			)
			(layer "F.Fab")
		)
		(pad "1" smd circle
			(at -0.40005 0 270)
			(size 0 0)
			(layers "F.Cu" "F.Mask" "F.Paste")
			(net "GND")
		)
		(pad "2" smd circle
			(at 0.40005 0 270)
			(size 0 0)
			(layers "F.Cu" "F.Mask" "F.Paste")
			(net "BIC_USB_8042_HUB_TEST")
		)
	)
	(footprint ""
		(layer "F.Cu")
		(at 28.633928 -350.098614 90)
		(property "Reference" "C2160"
			(at 0 0 90)
			(layer "F.SilkS")
			(hide yes)
			(effects
				(font
					(size 1.27 1.27)
				)
			)
		)
		(property "Value" ""
			(at 0 0 90)
			(layer "F.Fab")
			(effects
				(font
					(size 1.27 1.27)
				)
			)
		)
		(duplicate_pad_numbers_are_jumpers no)
		(fp_line
			(start 0.299974 -0.150114)
			(end 0.299974 0.150114)
			(stroke
				(width 0.1)
				(type default)
			)
			(layer "F.Fab")
		)
		(fp_line
			(start -0.299974 -0.150114)
			(end 0.299974 -0.150114)
			(stroke
				(width 0.1)
				(type default)
			)
			(layer "F.Fab")
		)
		(fp_line
			(start 0.299974 0.150114)
			(end -0.299974 0.150114)
			(stroke
				(width 0.1)
				(type default)
			)
			(layer "F.Fab")
		)
		(fp_line
			(start -0.299974 0.150114)
			(end -0.299974 -0.150114)
			(stroke
				(width 0.1)
				(type default)
			)
			(layer "F.Fab")
		)
		(pad "1" smd rect
			(at -0.2667 0 90)
			(size 0.3048 0.381)
			(layers "F.Cu" "F.Mask" "F.Paste")
			(net "P5E_PEX0_STN4_TX_DP<75>")
		)
		(pad "2" smd rect
			(at 0.2667 0 90)
			(size 0.3048 0.381)
			(layers "F.Cu" "F.Mask" "F.Paste")
			(net "P5E_PEX0_STN4_TX_C_DP<75>")
		)
	)
)
